FILE_TYPE = MACRO_DRAWING;
SET COLOR_WIRE YELLOW;
SET COLOR_PROP ORANGE;
SET COLOR_DOT WHITE;
SET COLOR_ARC YELLOW;
SET COLOR_BODY GREEN;
SET COLOR_NOTE PURPLE;
SET PROP_DISPLAY VALUE;
SET PAGE_NUMBER P6;
SET PATH_NUMBER P0;
FORCEADD QUANTA_TITLE_BLOCK_C..1
(4675 -1325);
FORCEPROP 0 LAST CDS_CON_LAST_MODIFIED Fri Aug 25 17:25:35 2023
J 0
(2790 -1310);
DISPLAY INVISIBLE (2790 -1310);
FORCEPROP 2 LAST Q_DEPT 
J 1
(912 -1276);
DISPLAY 1.957447 (912 -1276);
PAINT GREEN (912 -1276);
FORCEPROP 1 LAST CUSTOM_TXT_CDS <CON_LAST_MODIFIED>
J 0
(2790 -1310);
DISPLAY 0.978723 (2790 -1310);
FORCEPROP 2 LAST CUSTOM_TXT_CDS <XR_PAGE_TITLE>
J 0
(-3215 3925);
DISPLAY 0.638298 (-3215 3925);
PAINT PINK (-3215 3925);
DISPLAY INVISIBLE (-3215 3925);
FORCEPROP 1 LAST CUSTOM_TXT_CDS <NAME_2>
J 0
(1500 -1275);
FORCEPROP 1 LAST CUSTOM_TXT_CDS <NAME_1>
J 0
(1500 -1150);
FORCEPROP 1 LAST CUSTOM_TXT_CDS <Q_NUMBER>
J 0
(3272 -1222);
DISPLAY 1.212766 (3272 -1222);
FORCEPROP 1 LAST CUSTOM_TXT_CDS <Q_PROJ>
J 0
(2293 -1223);
DISPLAY 1.212766 (2293 -1223);
FORCEPROP 1 LAST CUSTOM_TXT_CDS <Q_REV>
J 0
(4491 -1222);
DISPLAY 1.212766 (4491 -1222);
FORCEPROP 1 LAST CUSTOM_TXT_CDS <CON_PAGE_NUM> OF <CON_TOTAL_PAGES>
J 0
(4229 -1307);
DISPLAY 0.978723 (4229 -1307);
FORCEPROP 1 LAST Q_TITLE I2C DIAGRAM
J 0
(-4700 -1300);
DISPLAY 2.446809 (-4700 -1300);
PAINT GREEN (-4700 -1300);
FORCEPROP 1 LAST COMMENT_BODY TRUE
J 0
(4687 -1338);
DISPLAY 0.978723 (4687 -1338);
PAINT PEACH (4687 -1338);
DISPLAY INVISIBLE (4687 -1338);
FORCEPROP 2 LAST PAGE_BORDER TRUE
J 0
(-3215 3925);
DISPLAY 0.638298 (-3215 3925);
PAINT PINK (-3215 3925);
DISPLAY INVISIBLE (-3215 3925);
FORCEPROP 1 LAST CDS_LMAN_SYM_OUTLINE -9475,6775,100,-125
J 0
(4675 -1325);
DISPLAY 0.468085 (4675 -1325);
PAINT GREEN (4675 -1325);
DISPLAY INVISIBLE (4675 -1325);
FORCEPROP 2 LAST CDS_LIB pure_quanta
J 0
(4675 -1325);
DISPLAY INVISIBLE (4675 -1325);
FORCEPROP 2 LAST CDS_XR_PAGE_TITLE CR-6 : @SCM_LIB.SCM(SCH_1):PAGE6
J 0
(-3215 3925);
DISPLAY 0.638298 (-3215 3925);
PAINT PINK (-3215 3925);
DISPLAY INVISIBLE (-3215 3925);
FORCENOTE
$CDS_IMAGE|F0T_SCM_I2C_V3.0.jpg|7345|6324
(-300 2150) 0;
DISPLAY LEFT (-300 2150);
QUIT
